(kicad_pcb
	(version 20260206)
	(generator "pcbnew")
	(generator_version "10.0")
	(general
		(thickness 1.6)
		(legacy_teardrops no)
	)
	(paper "A4")
	(title_block
		(title "v1-tray-backplane — T6M_tray_BP_c_1023_1120.brd")
		(comment 1 "Open CloudServer (Microsoft) / footprints 138-138 of 170")
	)
	(layers
		(0 "F.Cu" signal "TOP")
		(4 "In1.Cu" signal "GND")
		(6 "In2.Cu" signal "IN1")
		(8 "In3.Cu" signal "VCC")
		(10 "In4.Cu" signal "VCC1")
		(12 "In5.Cu" signal "IN2")
		(14 "In6.Cu" signal "GND1")
		(2 "B.Cu" signal "BOTTOM")
		(9 "F.Adhes" user "F.Adhesive")
		(11 "B.Adhes" user "B.Adhesive")
		(13 "F.Paste" user "Package Geometry/Pastemask Top")
		(15 "B.Paste" user "Package Geometry/Pastemask Bottom")
		(5 "F.SilkS" user "Ref Des/Silkscreen Top")
		(7 "B.SilkS" user "Ref Des/Silkscreen Bottom")
		(1 "F.Mask" user "Board Geometry/Soldermask Top")
		(3 "B.Mask" user "Board Geometry/Soldermask Bottom")
		(17 "Dwgs.User" user "User.Drawings")
		(19 "Cmts.User" user "User.Comments")
		(21 "Eco1.User" user "User.Eco1")
		(23 "Eco2.User" user "User.Eco2")
		(25 "Edge.Cuts" user "Board Geometry/Outline")
		(27 "Margin" user)
		(31 "F.CrtYd" user "Package Geometry/Place Bound Top")
		(29 "B.CrtYd" user "Package Geometry/Place Bound Bottom")
		(35 "F.Fab" user "Ref Des/Assembly Top")
		(33 "B.Fab" user "Ref Des/Assembly Bottom")
	)
	(footprint ""
		(layer "F.Cu")
		(at 123.535186 -44.8691 180)
		(property "Reference" "J22"
			(at -1.443228 -18.399252 0)
			(unlocked yes)
			(layer "F.SilkS")
			(effects
				(font
					(size 0.7874 0.5842)
					(thickness 0.1524)
				)
				(justify left)
			)
		)
		(property "Value" ""
			(at 0 0 180)
			(layer "F.Fab")
			(effects
				(font
					(size 1.27 1.27)
				)
			)
		)
		(duplicate_pad_numbers_are_jumpers no)
		(fp_line
			(start 9.655048 10.80008)
			(end 9.655048 6.1976)
			(stroke
				(width 0.1524)
				(type default)
			)
			(layer "F.SilkS")
		)
		(fp_line
			(start 9.655048 2.9718)
			(end 9.655048 -9.9822)
			(stroke
				(width 0.1524)
				(type default)
			)
			(layer "F.SilkS")
		)
		(fp_line
			(start 9.655048 -12.827)
			(end 9.655048 -17.649952)
			(stroke
				(width 0.1524)
				(type default)
			)
			(layer "F.SilkS")
		)
		(fp_line
			(start 9.655048 -17.649952)
			(end -9.655048 -17.649952)
			(stroke
				(width 0.1524)
				(type default)
			)
			(layer "F.SilkS")
		)
		(fp_line
			(start -9.655048 10.80008)
			(end 9.655048 10.80008)
			(stroke
				(width 0.1524)
				(type default)
			)
			(layer "F.SilkS")
		)
		(fp_line
			(start -9.655048 5.969)
			(end -9.655048 10.80008)
			(stroke
				(width 0.1524)
				(type default)
			)
			(layer "F.SilkS")
		)
		(fp_line
			(start -9.655048 0)
			(end -9.655048 3.1496)
			(stroke
				(width 0.1524)
				(type default)
			)
			(layer "F.SilkS")
		)
		(fp_line
			(start -9.655048 -17.649952)
			(end -9.655556 -16.722344)
			(stroke
				(width 0.1524)
				(type default)
			)
			(layer "F.SilkS")
		)
		(fp_line
			(start -9.656826 -14.280642)
			(end -9.663684 -0.70612)
			(stroke
				(width 0.1524)
				(type default)
			)
			(layer "F.SilkS")
		)
		(fp_line
			(start -9.663684 -0.70612)
			(end -9.655048 0)
			(stroke
				(width 0.1524)
				(type default)
			)
			(layer "F.SilkS")
		)
		(fp_poly
			(pts
				(xy -9.1313 -6.1341) (xy -11.2395 -6.7691) (xy -11.2395 -5.5245)
			)
			(stroke
				(width 0)
				(type default)
			)
			(fill yes)
			(layer "F.SilkS")
		)
		(fp_poly
			(pts
				(xy -3.9116 -9.6139) (xy -3.9116 -8.1788) (xy 5.1816 -8.1788) (xy 5.1816 -9.6139)
			)
			(stroke
				(width 0)
				(type default)
			)
			(fill no)
			(layer "B.CrtYd")
		)
		(fp_poly
			(pts
				(xy -3.9116 -16.2052) (xy -3.9116 -14.7701) (xy 5.1562 -14.7701) (xy 5.1562 -16.2052)
			)
			(stroke
				(width 0)
				(type default)
			)
			(fill no)
			(layer "B.CrtYd")
		)
		(fp_poly
			(pts
				(xy -5.1816 -7.0993) (xy -5.1816 -5.6388) (xy 3.9116 -5.6388) (xy 3.9116 -7.0993)
			)
			(stroke
				(width 0)
				(type default)
			)
			(fill no)
			(layer "B.CrtYd")
		)
		(fp_poly
			(pts
				(xy -5.1816 -13.6652) (xy -5.1816 -12.2428) (xy 3.9116 -12.2428) (xy 3.9116 -13.6652)
			)
			(stroke
				(width 0)
				(type default)
			)
			(fill no)
			(layer "B.CrtYd")
		)
		(fp_poly
			(pts
				(arc
					(start 6.931406 4.569968)
					(mid 10.078466 4.569968)
					(end 6.931406 4.569968)
				)
			)
			(stroke
				(width 0)
				(type default)
			)
			(fill no)
			(layer "B.CrtYd")
		)
		(fp_poly
			(pts
				(arc
					(start 6.928104 -11.43)
					(mid 10.081768 -11.43)
					(end 6.928104 -11.43)
				)
			)
			(stroke
				(width 0)
				(type default)
			)
			(fill no)
			(layer "B.CrtYd")
		)
		(fp_poly
			(pts
				(arc
					(start 6.167628 -5.839968)
					(mid 9.322308 -5.839968)
					(end 6.167628 -5.839968)
				)
			)
			(stroke
				(width 0)
				(type default)
			)
			(fill no)
			(layer "B.CrtYd")
		)
		(fp_poly
			(pts
				(arc
					(start -9.320784 -9.139936)
					(mid -6.169152 -9.139936)
					(end -9.320784 -9.139936)
				)
			)
			(stroke
				(width 0)
				(type default)
			)
			(fill no)
			(layer "B.CrtYd")
		)
		(fp_poly
			(pts
				(arc
					(start -10.076434 4.569968)
					(mid -6.933438 4.569968)
					(end -10.076434 4.569968)
				)
			)
			(stroke
				(width 0)
				(type default)
			)
			(fill no)
			(layer "B.CrtYd")
		)
		(fp_poly
			(pts
				(arc
					(start -10.080498 -15.489936)
					(mid -6.929374 -15.489936)
					(end -10.080498 -15.489936)
				)
			)
			(stroke
				(width 0)
				(type default)
			)
			(fill no)
			(layer "B.CrtYd")
		)
		(fp_poly
			(pts
				(arc
					(start 3.838194 0)
					(mid 7.591806 0)
					(end 3.838194 0)
				)
			)
			(stroke
				(width 0)
				(type default)
			)
			(fill no)
			(layer "B.CrtYd")
		)
		(fp_poly
			(pts
				(arc
					(start -7.590028 0)
					(mid -3.839972 0)
					(end -7.590028 0)
				)
			)
			(stroke
				(width 0)
				(type default)
			)
			(fill no)
			(layer "B.CrtYd")
		)
		(fp_poly
			(pts
				(xy -9.655048 0) (xy -9.655048 10.80008) (xy 9.655048 10.80008) (xy 9.655048 -17.649952) (xy -9.655048 -17.649952)
				(xy -9.663684 -0.70612)
			)
			(stroke
				(width 0)
				(type default)
			)
			(fill no)
			(layer "F.CrtYd")
		)
		(fp_text user "A7"
			(at 10.25398 -6.26491 90)
			(unlocked yes)
			(layer "F.SilkS")
			(effects
				(font
					(size 0.7874 0.5842)
					(thickness 0.1524)
				)
				(justify left)
			)
		)
		(fp_text user "A8"
			(at 10.22858 -9.03351 90)
			(unlocked yes)
			(layer "F.SilkS")
			(effects
				(font
					(size 0.7874 0.5842)
					(thickness 0.1524)
				)
				(justify left)
			)
		)
		(fp_text user "B2"
			(at 10.22477 -14.57071 90)
			(unlocked yes)
			(layer "F.SilkS")
			(effects
				(font
					(size 0.7874 0.5842)
					(thickness 0.1524)
				)
				(justify left)
			)
		)
		(fp_text user "B1"
			(at 9.899396 -18.835116 0)
			(unlocked yes)
			(layer "F.SilkS")
			(effects
				(font
					(size 0.7874 0.5842)
					(thickness 0.1524)
				)
				(justify left)
			)
		)
		(fp_text user "B7"
			(at -8.301228 -18.424652 0)
			(unlocked yes)
			(layer "F.SilkS")
			(effects
				(font
					(size 0.7874 0.5842)
					(thickness 0.1524)
				)
				(justify left)
			)
		)
		(fp_text user "A1"
			(at -10.268966 -4.752086 90)
			(unlocked yes)
			(layer "F.SilkS")
			(effects
				(font
					(size 0.7874 0.5842)
					(thickness 0.1524)
				)
				(justify left)
			)
		)
		(fp_text user "A2"
			(at -10.319766 -10.594086 90)
			(unlocked yes)
			(layer "F.SilkS")
			(effects
				(font
					(size 0.7874 0.5842)
					(thickness 0.1524)
				)
				(justify left)
			)
		)
		(fp_text user "B8"
			(at -10.345166 -13.489686 90)
			(unlocked yes)
			(layer "F.SilkS")
			(effects
				(font
					(size 0.7874 0.5842)
					(thickness 0.1524)
				)
				(justify left)
			)
		)
		(fp_text user "A8"
			(at 5.510784 -8.899906 0)
			(unlocked yes)
			(layer "B.SilkS")
			(effects
				(font
					(size 0.7874 0.5842)
					(thickness 0.1524)
				)
				(justify left mirror)
			)
		)
		(fp_text user "B1"
			(at 5.485384 -15.634716 0)
			(unlocked yes)
			(layer "B.SilkS")
			(effects
				(font
					(size 0.7874 0.5842)
					(thickness 0.1524)
				)
				(justify left mirror)
			)
		)
		(fp_text user "B2"
			(at 4.427982 -12.916916 0)
			(unlocked yes)
			(layer "B.SilkS")
			(effects
				(font
					(size 0.7874 0.5842)
					(thickness 0.1524)
				)
				(justify left mirror)
			)
		)
		(fp_text user "A7"
			(at 4.224782 -6.4643 0)
			(unlocked yes)
			(layer "B.SilkS")
			(effects
				(font
					(size 0.7874 0.5842)
					(thickness 0.1524)
				)
				(justify left mirror)
			)
		)
		(fp_text user "B7"
			(at -5.485638 -15.660116 0)
			(unlocked yes)
			(layer "B.SilkS")
			(effects
				(font
					(size 0.7874 0.5842)
					(thickness 0.1524)
				)
				(justify left mirror)
			)
		)
		(fp_text user "A2"
			(at -5.511038 -8.982202 0)
			(unlocked yes)
			(layer "B.SilkS")
			(effects
				(font
					(size 0.7874 0.5842)
					(thickness 0.1524)
				)
				(justify left mirror)
			)
		)
		(fp_text user "A1"
			(at -6.59384 -6.436106 0)
			(unlocked yes)
			(layer "B.SilkS")
			(effects
				(font
					(size 0.7874 0.5842)
					(thickness 0.1524)
				)
				(justify left mirror)
			)
		)
		(fp_text user "B8"
			(at -6.79704 -13.018516 0)
			(unlocked yes)
			(layer "B.SilkS")
			(effects
				(font
					(size 0.7874 0.5842)
					(thickness 0.1524)
				)
				(justify left mirror)
			)
		)
		(pad "" np_thru_hole circle
			(at -5.715 0 180)
			(size 3.2512 3.2512)
			(drill 3.2512)
			(layers "*.Cu" "*.Mask")
			(clearance 0.381)
			(thermal_gap 0.381)
		)
		(pad "" np_thru_hole circle
			(at 5.715 0 180)
			(size 3.2512 3.2512)
			(drill 3.2512)
			(layers "*.Cu" "*.Mask")
			(clearance 0.381)
			(thermal_gap 0.381)
		)
		(pad "A1" thru_hole rect
			(at -4.445 -6.35 180)
			(size 1.2954 1.2954)
			(drill 0.889)
			(layers "*.Cu" "*.Mask")
			(remove_unused_layers no)
			(net "ENET1G_1_MDI0P")
			(clearance 0.0508)
			(thermal_gap 0.0508)
			(padstack
				(mode front_inner_back)
				(layer "Inner"
					(shape circle)
					(size 1.2954 1.2954)
					(clearance 0.0508)
				)
				(layer "B.Cu"
					(shape rect)
					(size 1.2954 1.2954)
					(clearance 0.0508)
				)
			)
		)
		(pad "A2" thru_hole circle
			(at -3.175 -8.89 180)
			(size 1.2954 1.2954)
			(drill 0.889)
			(layers "*.Cu" "*.Mask")
			(remove_unused_layers no)
			(net "ENET1G_1_MDI0N")
			(clearance 0.0508)
			(thermal_gap 0.0508)
		)
		(pad "A3" thru_hole circle
			(at -1.905 -6.35 180)
			(size 1.2954 1.2954)
			(drill 0.889)
			(layers "*.Cu" "*.Mask")
			(remove_unused_layers no)
			(net "ENET1G_1_MDI1P")
			(clearance 0.0508)
			(thermal_gap 0.0508)
		)
		(pad "A4" thru_hole circle
			(at -0.635 -8.89 180)
			(size 1.2954 1.2954)
			(drill 0.889)
			(layers "*.Cu" "*.Mask")
			(remove_unused_layers no)
			(net "ENET1G_1_MDI2P")
			(clearance 0.0508)
			(thermal_gap 0.0508)
		)
		(pad "A5" thru_hole circle
			(at 0.635 -6.35 180)
			(size 1.2954 1.2954)
			(drill 0.889)
			(layers "*.Cu" "*.Mask")
			(remove_unused_layers no)
			(net "ENET1G_1_MDI2N")
			(clearance 0.0508)
			(thermal_gap 0.0508)
		)
		(pad "A6" thru_hole circle
			(at 1.905 -8.89 180)
			(size 1.2954 1.2954)
			(drill 0.889)
			(layers "*.Cu" "*.Mask")
			(remove_unused_layers no)
			(net "ENET1G_1_MDI1N")
			(clearance 0.0508)
			(thermal_gap 0.0508)
		)
		(pad "A7" thru_hole circle
			(at 3.175 -6.35 180)
			(size 1.2954 1.2954)
			(drill 0.889)
			(layers "*.Cu" "*.Mask")
			(remove_unused_layers no)
			(net "ENET1G_1_MDI3P")
			(clearance 0.0508)
			(thermal_gap 0.0508)
		)
		(pad "A8" thru_hole circle
			(at 4.445 -8.89 180)
			(size 1.2954 1.2954)
			(drill 0.889)
			(layers "*.Cu" "*.Mask")
			(remove_unused_layers no)
			(net "ENET1G_1_MDI3N")
			(clearance 0.0508)
			(thermal_gap 0.0508)
		)
		(pad "B1" thru_hole circle
			(at 4.445 -15.489936 180)
			(size 1.2954 1.2954)
			(drill 0.889)
			(layers "*.Cu" "*.Mask")
			(remove_unused_layers no)
			(net "ENET1G_2_MDI0P")
			(clearance 0.0508)
			(thermal_gap 0.0508)
		)
		(pad "B2" thru_hole circle
			(at 3.175 -12.949936 180)
			(size 1.2954 1.2954)
			(drill 0.889)
			(layers "*.Cu" "*.Mask")
			(remove_unused_layers no)
			(net "ENET1G_2_MDI0N")
			(clearance 0.0508)
			(thermal_gap 0.0508)
		)
		(pad "B3" thru_hole circle
			(at 1.905 -15.489936 180)
			(size 1.2954 1.2954)
			(drill 0.889)
			(layers "*.Cu" "*.Mask")
			(remove_unused_layers no)
			(net "ENET1G_2_MDI1P")
			(clearance 0.0508)
			(thermal_gap 0.0508)
		)
		(pad "B4" thru_hole circle
			(at 0.635 -12.949936 180)
			(size 1.2954 1.2954)
			(drill 0.889)
			(layers "*.Cu" "*.Mask")
			(remove_unused_layers no)
			(net "ENET1G_2_MDI2P")
			(clearance 0.0508)
			(thermal_gap 0.0508)
		)
		(pad "B5" thru_hole circle
			(at -0.635 -15.489936 180)
			(size 1.2954 1.2954)
			(drill 0.889)
			(layers "*.Cu" "*.Mask")
			(remove_unused_layers no)
			(net "ENET1G_2_MDI2N")
			(clearance 0.0508)
			(thermal_gap 0.0508)
		)
		(pad "B6" thru_hole circle
			(at -1.905 -12.949936 180)
			(size 1.2954 1.2954)
			(drill 0.889)
			(layers "*.Cu" "*.Mask")
			(remove_unused_layers no)
			(net "ENET1G_2_MDI1N")
			(clearance 0.0508)
			(thermal_gap 0.0508)
		)
		(pad "B7" thru_hole circle
			(at -3.175 -15.489936 180)
			(size 1.2954 1.2954)
			(drill 0.889)
			(layers "*.Cu" "*.Mask")
			(remove_unused_layers no)
			(net "ENET1G_2_MDI3P")
			(clearance 0.0508)
			(thermal_gap 0.0508)
		)
		(pad "B8" thru_hole circle
			(at -4.445 -12.949936 180)
			(size 1.2954 1.2954)
			(drill 0.889)
			(layers "*.Cu" "*.Mask")
			(remove_unused_layers no)
			(net "ENET1G_2_MDI3N")
			(clearance 0.0508)
			(thermal_gap 0.0508)
		)
		(pad "G1" thru_hole circle
			(at -8.504936 -15.489936 180)
			(size 3.048 3.048)
			(drill 2.032)
			(layers "*.Cu" "*.Mask")
			(remove_unused_layers no)
			(net "GND")
			(clearance -0.254)
		)
		(pad "G2" thru_hole circle
			(at -7.744968 -9.139936 180)
			(size 3.048 3.048)
			(drill 2.032)
			(layers "*.Cu" "*.Mask")
			(remove_unused_layers no)
			(net "GND")
			(clearance -0.254)
		)
		(pad "G3" thru_hole circle
			(at -8.504936 4.569968 180)
			(size 3.048 3.048)
			(drill 2.032)
			(layers "*.Cu" "*.Mask")
			(remove_unused_layers no)
			(net "GND")
			(clearance -0.254)
		)
		(pad "G4" thru_hole circle
			(at 8.504936 4.569968 180)
			(size 3.048 3.048)
			(drill 2.032)
			(layers "*.Cu" "*.Mask")
			(remove_unused_layers no)
			(net "GND")
			(clearance -0.254)
		)
		(pad "G5" thru_hole circle
			(at 7.744968 -5.839968 180)
			(size 3.048 3.048)
			(drill 2.032)
			(layers "*.Cu" "*.Mask")
			(remove_unused_layers no)
			(net "GND")
			(clearance -0.254)
		)
		(pad "G6" thru_hole circle
			(at 8.504936 -11.43 180)
			(size 3.048 3.048)
			(drill 2.032)
			(layers "*.Cu" "*.Mask")
			(remove_unused_layers no)
			(net "GND")
			(clearance -0.254)
		)
		(zone
			(layers "F.Cu" "B.Cu" "In1.Cu" "In2.Cu" "In3.Cu" "In4.Cu" "In5.Cu" "In6.Cu")
			(hatch none 0.5)
			(connect_pads
				(clearance 0)
			)
			(min_thickness 0.25)
			(keepout
				(tracks not_allowed)
				(vias allowed)
				(pads allowed)
				(copperpour not_allowed)
				(footprints allowed)
			)
			(placement
				(enabled no)
				(sheetname "")
			)
			(fill
				(thermal_gap 0.5)
				(thermal_bridge_width 0.5)
				(island_removal_mode 0)
			)
			(polygon
				(pts
					(arc
						(start 119.854472 -44.8691)
						(mid 115.7859 -44.8691)
						(end 119.854472 -44.8691)
					)
				)
			)
		)
		(zone
			(layers "F.Cu" "B.Cu" "In1.Cu" "In2.Cu" "In3.Cu" "In4.Cu" "In5.Cu" "In6.Cu")
			(hatch none 0.5)
			(connect_pads
				(clearance 0)
			)
			(min_thickness 0.25)
			(keepout
				(tracks not_allowed)
				(vias allowed)
				(pads allowed)
				(copperpour not_allowed)
				(footprints allowed)
			)
			(placement
				(enabled no)
				(sheetname "")
			)
			(fill
				(thermal_gap 0.5)
				(thermal_bridge_width 0.5)
				(island_removal_mode 0)
			)
			(polygon
				(pts
					(arc
						(start 131.282694 -44.8691)
						(mid 127.217678 -44.8691)
						(end 131.282694 -44.8691)
					)
				)
			)
		)
	)
)
